# S9S_MB_2U (Grand Teton) — schematic parts with pin connectivity, parts 2534–2658 of 6093; source: Cadence DE-HDL packaged netlist (pstxprt.dat, pstxnet.dat, pstchip.dat)

PL3  Q_INDUCTOR  300NH/33A IND  pkg SMLF  page 276 : 1 = SW_PVCCFA_EHV_CPU0_SW1 ; 2 = PVCCFA_EHV_CPU0
PL4  Q_INDUCTOR  120NH/69A IND  pkg SMLF  page 275 : 1 = SW_PVCCINFAON_CPU0_SW1 ; 2 = PVCCINFAON_CPU0
PL5  Q_INDUCTOR  120NH/69A IND  pkg SMLF  page 275 : 1 = SW_PVCCINFAON_CPU0_SW2 ; 2 = PVCCINFAON_CPU0
PL6  Q_INDUCTOR  100NH/16A IND  pkg SMLF  page 275 : 1 = P12V_AUX ; 2 = SW_P12V_PVCCINFAON_CPU0_FLT

PL7  Q_INDUCTOR4P_14  150NH IND  pkg L_TLM117513Q-151QL_11X7-5XA  page 270
  1  \1\  BI  = SW_PVCCIN_CPU0_SW8
  2  \2\  BI  = IND_P0_CPL8
  3  \3\  BI  = GND
  4  \4\  BI  = PVCCIN_CPU0

PL8  Q_INDUCTOR4P_14  150NH IND  pkg L_TLM117513Q-151QL_11X7-5XA  page 270
  1  \1\  BI  = SW_PVCCIN_CPU0_SW7
  2  \2\  BI  = IND_P0_CPL7
  3  \3\  BI  = IND_P0_CPL6
  4  \4\  BI  = PVCCIN_CPU0

PL9  Q_INDUCTOR4P_14  150NH IND  pkg L_TLM117513Q-151QL_11X7-5XA  page 269
  1  \1\  BI  = SW_PVCCIN_CPU0_SW6
  2  \2\  BI  = IND_P0_CPL6
  3  \3\  BI  = IND_P0_CPL1
  4  \4\  BI  = PVCCIN_CPU0

PL10  Q_INDUCTOR4P_14  150NH IND  pkg L_TLM117513Q-151QL_11X7-5XA  page 269
  1  \1\  BI  = SW_PVCCIN_CPU0_SW5
  2  \2\  BI  = IND_P0_CPL5
  3  \3\  BI  = IND_P0_CPL8
  4  \4\  BI  = PVCCIN_CPU0

PL11  Q_INDUCTOR4P_14  150NH IND  pkg L_TLM117513Q-151QL_11X7-5XA  page 268
  1  \1\  BI  = SW_PVCCIN_CPU0_SW4
  2  \2\  BI  = IND_P0_CPL4
  3  \3\  BI  = IND_P0_CPL5
  4  \4\  BI  = PVCCIN_CPU0

PL12  Q_INDUCTOR  130NH/106A IND  pkg SMLF  page 290 : 1 = SW_PVCCFA_EHV_FIVRA_CPU1_SW3 ; 2 = PVCCFA_EHV_FIVRA_CPU1

PL13  Q_INDUCTOR4P_14  150NH IND  pkg L_TLM117513Q-151QL_11X7-5XA  page 267
  1  \1\  BI  = SW_PVCCIN_CPU0_SW2
  2  \2\  BI  = IND_P0_CPL2
  3  \3\  BI  = IND_P0_CPL3
  4  \4\  BI  = PVCCIN_CPU0

PL14  Q_INDUCTOR  100NH/16A IND  pkg SMLF  page 290 : 1 = P12V_AUX ; 2 = SW_P12V_PVCCFA_EHV_FIVRA_CPU1_R
PL15  Q_INDUCTOR  50NH/148A IND  pkg SMLF  page 267 : 1 = P12V_AUX ; 2 = SW_P12V_PVCCIN_CPU0_FLT
PL16  Q_INDUCTOR  BLM18SN220TN1D/8000MA IND  pkg SMLF  page 263 : 1 = P12V_AUX ; 2 = SW_P1V8_PCH_AUX_FLT
PL17  Q_INDUCTOR  120NH/69A IND  pkg SMLF  page 297 : 1 = SW_PVCCD_HV_CPU1_SW1 ; 2 = PVCCD_HV_CPU1
PL18  Q_INDUCTOR  130NH/106A IND  pkg SMLF  page 289 : 1 = SW_PVCCFA_EHV_FIVRA_CPU1_SW1 ; 2 = PVCCFA_EHV_FIVRA_CPU1
PL19  Q_INDUCTOR  130NH/106A IND  pkg SMLF  page 289 : 1 = SW_PVCCFA_EHV_FIVRA_CPU1_SW2 ; 2 = PVCCFA_EHV_FIVRA_CPU1
PL20  Q_INDUCTOR  300NH/33A IND  pkg SMLF  page 294 : 1 = SW_PVCCFA_EHV_CPU1_SW1 ; 2 = PVCCFA_EHV_CPU1
PL21  Q_INDUCTOR  120NH/69A IND  pkg SMLF  page 293 : 1 = SW_PVCCINFAON_CPU1_SW1 ; 2 = PVCCINFAON_CPU1
PL22  Q_INDUCTOR  120NH/69A IND  pkg SMLF  page 293 : 1 = SW_PVCCINFAON_CPU1_SW2 ; 2 = PVCCINFAON_CPU1
PL23  Q_INDUCTOR  100NH/16A IND  pkg SMLF  page 293 : 1 = P12V_AUX ; 2 = SW_P12V_PVCCINFAON_CPU1_FLT

PL24  Q_INDUCTOR4P_14  150NH IND  pkg L_TLM117513Q-151QL_11X7-5XA  page 288
  1  \1\  BI  = SW_PVCCIN_CPU1_SW8
  2  \2\  BI  = IND_P1_CPL8
  3  \3\  BI  = IND_P1_CPL5
  4  \4\  BI  = PVCCIN_CPU1

PL25  Q_INDUCTOR4P_14  150NH IND  pkg L_TLM117513Q-151QL_11X7-5XA  page 288
  1  \1\  BI  = SW_PVCCIN_CPU1_SW7
  2  \2\  BI  = IND_P1_CPL7
  3  \3\  BI  = GND
  4  \4\  BI  = PVCCIN_CPU1

PL26  Q_INDUCTOR4P_14  150NH IND  pkg L_TLM117513Q-151QL_11X7-5XA  page 287
  1  \1\  BI  = SW_PVCCIN_CPU1_SW6
  2  \2\  BI  = IND_P1_CPL6
  3  \3\  BI  = IND_P1_CPL7
  4  \4\  BI  = PVCCIN_CPU1

PL27  Q_INDUCTOR4P_14  150NH IND  pkg L_TLM117513Q-151QL_11X7-5XA  page 287
  1  \1\  BI  = SW_PVCCIN_CPU1_SW5
  2  \2\  BI  = IND_P1_CPL5
  3  \3\  BI  = IND_P1_CPL4
  4  \4\  BI  = PVCCIN_CPU1

PL28  Q_INDUCTOR4P_14  150NH IND  pkg L_TLM117513Q-151QL_11X7-5XA  page 286
  1  \1\  BI  = SW_PVCCIN_CPU1_SW4
  2  \2\  BI  = IND_P1_CPL4
  3  \3\  BI  = IND_P1_CPL3
  4  \4\  BI  = PVCCIN_CPU1

PL29  Q_INDUCTOR4P_14  150NH IND  pkg L_TLM117513Q-151QL_11X7-5XA  page 286
  1  \1\  BI  = SW_PVCCIN_CPU1_SW3
  2  \2\  BI  = IND_P1_CPL3
  3  \3\  BI  = IND_P1_CPL2
  4  \4\  BI  = PVCCIN_CPU1

PL30  Q_INDUCTOR4P_14  150NH IND  pkg L_TLM117513Q-151QL_11X7-5XA  page 285
  1  \1\  BI  = SW_PVCCIN_CPU1_SW2
  2  \2\  BI  = IND_P1_CPL2
  3  \3\  BI  = IND_P1_CPL1
  4  \4\  BI  = PVCCIN_CPU1

PL31  Q_INDUCTOR4P_14  150NH IND  pkg L_TLM117513Q-151QL_11X7-5XA  page 285
  1  \1\  BI  = SW_PVCCIN_CPU1_SW1
  2  \2\  BI  = IND_P1_CPL1
  3  \3\  BI  = IND_P1_CPL6
  4  \4\  BI  = PVCCIN_CPU1

PL32  Q_INDUCTOR  50NH/148A IND  pkg SMLF  page 285 : 1 = P12V_AUX ; 2 = SW_P12V_PVCCIN_CPU1_FLT
PL33  Q_INDUCTOR  130NH/106A IND  pkg SMLF  page 271 : 1 = SW_PVCCFA_EHV_FIVRA_CPU0_SW1 ; 2 = PVCCFA_EHV_FIVRA_CPU0
PL34  Q_INDUCTOR  130NH/106A IND  pkg SMLF  page 271 : 1 = SW_PVCCFA_EHV_FIVRA_CPU0_SW2 ; 2 = PVCCFA_EHV_FIVRA_CPU0
PL35  Q_INDUCTOR  120NH/69A IND  pkg SMLF  page 279 : 1 = SW_PVCCD_HV_CPU0_SW1 ; 2 = PVCCD_HV_CPU0
PL43  Q_INDUCTOR  100NH/16A IND  pkg SMLF  page 289 : 1 = P12V_AUX ; 2 = SW_P12V_PVCCFA_EHV_FIVRA_CPU1_L
PL44  Q_INDUCTOR  100NH/16A IND  pkg SMLF  page 271 : 1 = P12V_AUX ; 2 = SW_P12V_PVCCFA_EHV_FIVRA_CPU0_L
PL45  Q_INDUCTOR  100NH/16A IND  pkg SMLF  page 259 : 1 = P12V_AUX ; 2 = SW_P3V3_AUX_FLT
PL64  Q_INDUCTOR  BLM18SN220TN1D/8000MA IND  pkg SMLF  page 258 : 1 = P12V_AUX ; 2 = SW_P5V_AUX_FLT
PL65  Q_INDUCTOR  4.7UH IND  pkg SMLF  page 258 : 1 = SW_P5V_AUX_SW ; 2 = P5V_AUX
PL66  Q_INDUCTOR  1.5UH/53A IND  pkg SMLF  page 259 : 1 = SW_P3V3_AUX_SW ; 2 = P3V3_AUX
PL101  Q_INDUCTOR  100NH/16A IND  pkg SMLF  page 272 : 1 = P12V_AUX ; 2 = SW_P12V_PVCCFA_EHV_FIVRA_CPU0_R
PL105  Q_INDUCTOR  120NH/69A IND  pkg SMLF  page 270 : 1 = IND_P0_CPL7 ; 2 = GND
PL106  Q_INDUCTOR  120NH/69A IND  pkg SMLF  page 288 : 1 = IND_P1_CPL8 ; 2 = GND
PL110  Q_INDUCTOR  100NH/16A IND  pkg SMLF  page 262 : 1 = P12V_AUX ; 2 = SW_P12V_AUX_P1V05_PCH_AUX_FLT

PL112  Q_INDUCTOR4P_14  150NH IND  pkg L_TLM117513Q-151QL_11X7-5XA  page 268
  1  \1\  BI  = SW_PVCCIN_CPU0_SW3
  2  \2\  BI  = IND_P0_CPL3
  3  \3\  BI  = IND_P0_CPL4
  4  \4\  BI  = PVCCIN_CPU0

PL113  Q_INDUCTOR  130NH/106A IND  pkg SMLF  page 290 : 1 = SW_PVCCFA_EHV_FIVRA_CPU1_SW4 ; 2 = PVCCFA_EHV_FIVRA_CPU1

PL114  Q_INDUCTOR4P_14  150NH IND  pkg L_TLM117513Q-151QL_11X7-5XA  page 267
  1  \1\  BI  = SW_PVCCIN_CPU0_SW1
  2  \2\  BI  = IND_P0_CPL1
  3  \3\  BI  = IND_P0_CPL2
  4  \4\  BI  = PVCCIN_CPU0

PL118  Q_INDUCTOR  0.68UH IND  pkg SMLF  page 281 : 1 = SW_PVPP_HBM_CPU0_SW ; 2 = PVPP_HBM_CPU0
PL119  Q_INDUCTOR  0.68UH IND  pkg SMLF  page 299 : 1 = SW_PVPP_HBM_CPU1_SW ; 2 = PVPP_HBM_CPU1
PL120  Q_INDUCTOR  4.7UH IND  pkg SMLF  page 282 : 1 = SW_PVNN_MAIN_CPU0_SW ; 2 = PVNN_MAIN_CPU0
PL121  Q_INDUCTOR  4.7UH IND  pkg SMLF  page 300 : 1 = SW_PVNN_MAIN_CPU1_SW ; 2 = PVNN_MAIN_CPU1
PL150  Q_INDUCTOR  300NH/33A IND  pkg SMLF  page 262 : 1 = SW_P1V05_PCH_AUX_SW ; 2 = P1V05_PCH_AUX
PL170  Q_INDUCTOR  2.2UH IND  pkg SMLF  page 263 : 1 = SW_P1V8_PCH_AUX_SW ; 2 = P1V8_PCH_AUX
PL210  Q_INDUCTOR  130NH/106A IND  pkg SMLF  page 272 : 1 = SW_PVCCFA_EHV_FIVRA_CPU0_SW4 ; 2 = PVCCFA_EHV_FIVRA_CPU0

PPQ1  MOSFET_NCH_1D3S  PSMNR58-30YLH EMPTY  pkg SOT1023  page 304
  1  \1\  BI  = P12V_AUX
  2  \2\  BI  = P12V_AUX
  3  \3\  BI  = P12V_AUX
  4  \4\  IN  = P12V_HSC_GATE_G5
  5  \5\  BI  = P12V_MAIN_R

PPQ2  MOSFET_NCH_1D3S  PSMNR58-30YLH EMPTY  pkg SOT1023  page 304
  1  \1\  BI  = P12V_AUX
  2  \2\  BI  = P12V_AUX
  3  \3\  BI  = P12V_AUX
  4  \4\  IN  = P12V_HSC_GATE_G6
  5  \5\  BI  = P12V_MAIN_R

PPQ5  MOSFET_NCH_1D3S  PSMNR58-30YLH EMPTY  pkg SOT1023  page 304
  1  \1\  BI  = P12V_AUX
  2  \2\  BI  = P12V_AUX
  3  \3\  BI  = P12V_AUX
  4  \4\  IN  = P12V_HSC_GATE_G1
  5  \5\  BI  = P12V_MAIN_R

PPQ6  MOSFET_NCH_1D3S  PSMNR58-30YLH EMPTY  pkg SOT1023  page 304
  1  \1\  BI  = P12V_AUX
  2  \2\  BI  = P12V_AUX
  3  \3\  BI  = P12V_AUX
  4  \4\  IN  = P12V_HSC_GATE_G2
  5  \5\  BI  = P12V_MAIN_R

PPQ7  MOSFET_NCH_1D3S  PSMNR58-30YLH EMPTY  pkg SOT1023  page 304
  1  \1\  BI  = P12V_AUX
  2  \2\  BI  = P12V_AUX
  3  \3\  BI  = P12V_AUX
  4  \4\  IN  = P12V_HSC_GATE_G3
  5  \5\  BI  = P12V_MAIN_R

PPQ8  MOSFET_NCH_1D3S  PSMNR58-30YLH EMPTY  pkg SOT1023  page 304
  1  \1\  BI  = P12V_AUX
  2  \2\  BI  = P12V_AUX
  3  \3\  BI  = P12V_AUX
  4  \4\  IN  = P12V_HSC_GATE_G4
  5  \5\  BI  = P12V_MAIN_R

PPQ9  MOSFET_NCH_1D3S  PSMNR58-30YLH EMPTY  pkg SOT1023  page 304
  1  \1\  BI  = P12V_AUX
  2  \2\  BI  = P12V_AUX
  3  \3\  BI  = P12V_AUX
  4  \4\  IN  = MB0_CM_GATE_G0
  5  \5\  BI  = P12V_MAIN_R_0

PR1  Q_RES  0 5% CHIP  pkg 0402LF  page 282 : 1 = GND ; 2 = GND
PR2  Q_RES  0 5% CHIP  pkg 0402LF  page 300 : 1 = GND ; 2 = GND

PR3  Q_RES_4P_12  0.003 1% EMPTY  pkg R2512_4P_H41  page 304
  1  \1\  UNSPEC  = P12V_PSU
  2  \2\  UNSPEC  = P12V_MAIN_R_0
  3  \3\  UNSPEC  = P12V_HSC_SENSE1_P
  4  \4\  UNSPEC  = P12V_HSC_SENSE1_N

PR4  Q_SP_RES4P  0.0003 1% EMPTY  pkg R2725_4P  page 304
  1A  \1a\  BI  = P12V_PSU
  1B  \1b\  BI  = P12V_HSC_SENSE2_R1_P
  2A  \2a\  BI  = P12V_MAIN_R
  2B  \2b\  BI  = P12V_HSC_SENSE2_R1_N

PR50  Q_RES  12.4K 0.1% CHIP  pkg 0402LF  page 282 : 1 = PVNN_MAIN_CPU0_FB ; 2 = GND
PR51  Q_RES  12.4K 0.1% CHIP  pkg 0402LF  page 300 : 1 = PVNN_MAIN_CPU1_FB ; 2 = GND
PR73  Q_RES  10K 1% CHIP  pkg 0402LF  page 259 : 1 = P3V3_AUX ; 2 = PWRGD_P3V3_AUX
PR89  Q_RES  16.9K 1% CHIP  pkg 0402LF  page 258 : 1 = P5V_AUX_CS ; 2 = GND
PR91  Q_RES  11.8K 0.1% CHIP  pkg 0402LF  page 258 : 1 = P5V_AUX_FB ; 2 = GND
PR92  Q_RES  88.7K 1% CHIP  pkg 0402LF  page 258 : 1 = P5V_AUX_FB ; 2 = P5V_AUX
PR97  Q_RES  2.2 1% CHIP  pkg 0402LF  page 276 : 1 = PVCCFA_EHV_CPU0_PVCC ; 2 = PVCCFA_EHV_CPU0_VDD1
PR101  Q_RES  2.2 1% CHIP  pkg 0402LF  page 275 : 1 = PVCCFA_EHV_CPU0_PVCC ; 2 = PVCCINFAON_CPU0_VDD1
PR102  Q_RES  2.2 1% CHIP  pkg 0402LF  page 275 : 1 = PVCCFA_EHV_CPU0_PVCC ; 2 = PVCCINFAON_CPU0_VDD2
PR105  Q_RES  28K 1% EMPTY  pkg 0402LF  page 274 : 1 = PVCCINFAON_CPU0_VREF ; 2 = PVCCINFAON_CPU0_ADDR
PR106  Q_RES  681 1% CHIP  pkg 0402LF  page 274 : 1 = PVCCINFAON_CPU0_ADDR ; 2 = GND
PR107  Q_RES  0 5% EMPTY  pkg 0402LF  page 274 : 1 = P12V_AUX ; 2 = PVCCINFAON_CPU0_CSPIN
PR108  Q_RES  0 5% CHIP  pkg 0402LF  page 274 : 1 = P12V_AUX ; 2 = PVCCINFAON_CPU0_VIN_CSNIN
PR120  Q_RES  0 5% CHIP  pkg 0402LF  page 274 : 1 = SH_PVCCINFAON_CPU0 ; 2 = SH_PVCCINFAON_CPU0_R
PR121  Q_RES  0 5% CHIP  pkg 0402LF  page 274 : 1 = SH_PVCCFA_EHV_CPU0 ; 2 = SH_PVCCFA_EHV_CPU0_R
PR123  Q_RES  1K 1% EMPTY  pkg 0402LF  page 274 : 1 = PVCCINFAON_CPU0_VIN_CSNIN ; 2 = GND
PR130  Q_RES  1 1% CHIP  pkg 0402LF  page 274 : 1 = PVCCINFAON_CPU0_VCC ; 2 = P3V3_AUX
PR132  Q_RES  8.87K 1% EMPTY  pkg 0402LF  page 270 : 1 = PVCCIN_CPU0_LSET8 ; 2 = GND
PR133  Q_RES  8.87K 1% EMPTY  pkg 0402LF  page 270 : 1 = PVCCIN_CPU0_LSET7 ; 2 = GND
PR134  Q_RES  2.2 1% CHIP  pkg 0402LF  page 270 : 1 = PVCCIN_CPU0_PVCC ; 2 = PVCCIN_CPU0_VDD8
PR135  Q_RES  2.2 1% CHIP  pkg 0402LF  page 270 : 1 = PVCCIN_CPU0_PVCC ; 2 = PVCCIN_CPU0_VDD7
PR136  Q_RES  0 5% CHIP  pkg 0402LF  page 270 : 1 = PVCCIN_CPU0_VOS8 ; 2 = PVCCIN_CPU0
PR137  Q_RES  0 5% CHIP  pkg 0402LF  page 270 : 1 = PVCCIN_CPU0_VOS7 ; 2 = PVCCIN_CPU0
PR138  Q_RES  8.87K 1% EMPTY  pkg 0402LF  page 269 : 1 = PVCCIN_CPU0_LSET6 ; 2 = GND
PR139  Q_RES  8.87K 1% EMPTY  pkg 0402LF  page 269 : 1 = PVCCIN_CPU0_LSET5 ; 2 = GND
PR140  Q_RES  2.2 1% CHIP  pkg 0402LF  page 269 : 1 = PVCCIN_CPU0_PVCC ; 2 = PVCCIN_CPU0_VDD6
PR141  Q_RES  2.2 1% CHIP  pkg 0402LF  page 269 : 1 = PVCCIN_CPU0_PVCC ; 2 = PVCCIN_CPU0_VDD5
PR142  Q_RES  0 5% CHIP  pkg 0402LF  page 269 : 1 = PVCCIN_CPU0_VOS6 ; 2 = PVCCIN_CPU0
PR143  Q_RES  0 5% CHIP  pkg 0402LF  page 269 : 1 = PVCCIN_CPU0_VOS5 ; 2 = PVCCIN_CPU0
PR144  Q_RES  8.87K 1% EMPTY  pkg 0402LF  page 268 : 1 = PVCCIN_CPU0_LSET4 ; 2 = GND
PR145  Q_RES  8.87K 1% EMPTY  pkg 0402LF  page 268 : 1 = PVCCIN_CPU0_LSET3 ; 2 = GND
PR146  Q_RES  2.2 1% CHIP  pkg 0402LF  page 268 : 1 = PVCCIN_CPU0_PVCC ; 2 = PVCCIN_CPU0_VDD4
PR147  Q_RES  2.2 1% CHIP  pkg 0402LF  page 268 : 1 = PVCCIN_CPU0_PVCC ; 2 = PVCCIN_CPU0_VDD3
PR148  Q_RES  0 5% CHIP  pkg 0402LF  page 268 : 1 = PVCCIN_CPU0_VOS4 ; 2 = PVCCIN_CPU0
PR149  Q_RES  0 5% CHIP  pkg 0402LF  page 268 : 1 = PVCCIN_CPU0_VOS3 ; 2 = PVCCIN_CPU0
PR150  Q_RES  8.87K 1% EMPTY  pkg 0402LF  page 267 : 1 = PVCCIN_CPU0_LSET2 ; 2 = GND
PR151  Q_RES  8.87K 1% EMPTY  pkg 0402LF  page 267 : 1 = PVCCIN_CPU0_LSET1 ; 2 = GND
PR152  Q_RES  2.2 1% CHIP  pkg 0402LF  page 267 : 1 = PVCCIN_CPU0_PVCC ; 2 = PVCCIN_CPU0_VDD2
PR153  Q_RES  2.2 1% CHIP  pkg 0402LF  page 267 : 1 = PVCCIN_CPU0_PVCC ; 2 = PVCCIN_CPU0_VDD1
PR154  Q_RES  0 5% CHIP  pkg 0402LF  page 267 : 1 = PVCCIN_CPU0_VOS2 ; 2 = PVCCIN_CPU0
PR155  Q_RES  0 5% CHIP  pkg 0402LF  page 267 : 1 = PVCCIN_CPU0_VOS1 ; 2 = PVCCIN_CPU0
PR156  Q_RES  0 5% CHIP  pkg 0402LF  page 266 : 1 = P12V_AUX ; 2 = PVCCIN_CPU0_VIN_CSNIN
PR157  Q_RES  0 5% EMPTY  pkg 0402LF  page 266 : 1 = P12V_AUX ; 2 = PVCCIN_CPU0_CSPIN
PR158  Q_RES  0 5% CHIP  pkg 0402LF  page 266 : 1 = PVCCIN_CPU0_CSPIN ; 2 = GND
PR159  Q_RES  28K 1% EMPTY  pkg 0402LF  page 266 : 1 = PVCCIN_CPU0_VREF ; 2 = PVCCIN_CPU0_ADDR
PR166  Q_RES  1K 1% EMPTY  pkg 0402LF  page 266 : 1 = PVCCIN_CPU0_VIN_CSNIN ; 2 = GND
PR170  Q_RES  0 5% CHIP  pkg 0402LF  page 266 : 1 = SH_PVCCIN_CPU0 ; 2 = SH_PVCCIN_CPU0_R
PR171  Q_RES  0 5% CHIP  pkg 0402LF  page 266 : 1 = PVCCIN_CPU0_ADDR ; 2 = GND
PR176  Q_RES  1 1% CHIP  pkg 0402LF  page 266 : 1 = PVCCIN_CPU0_VCC ; 2 = P3V3_AUX
PR187  Q_RES  10K 0.1% CHIP  pkg 0402LF  page 262 : 1 = P1V05_PCH_AUX_FB ; 2 = SH_P1V05_PCH_AUX_N
PR200  Q_RES  2.2 1% CHIP  pkg 0402LF  page 297 : 1 = PVCCFA_EHV_CPU1_PVCC ; 2 = PVCCD_HV_CPU1_VDD1
PR202  Q_RES  28K 1% EMPTY  pkg 0402LF  page 296 : 1 = PVCCD_HV_CPU1_VREF ; 2 = PVCCD_HV_CPU1_ADDR
PR203  Q_RES  24.3K 1% CHIP  pkg 0402LF  page 296 : 1 = GND ; 2 = PVCCD_HV_CPU1_ADDR
PR214  Q_RES  1K 1% EMPTY  pkg 0402LF  page 296 : 1 = PVCCD_HV_CPU1_ISENSE_P ; 2 = GND
PR215  Q_RES  1K 1% CHIP  pkg 0402LF  page 296 : 1 = P3V3_AUX ; 2 = PVCCD_HV_CPU1_PIN_ALT
PR216  Q_RES  0 5% CHIP  pkg 0402LF  page 296 : 1 = SH_PVCCD_HV_CPU1 ; 2 = SH_PVCCD_HV_CPU1_R
PR217  Q_RES  1K 1% CHIP  pkg 0402LF  page 296 : 1 = P3V3_AUX ; 2 = PVCCD_HV_CPU1_FAULT
PR218  Q_RES  1K 1% EMPTY  pkg 0402LF  page 296 : 1 = PVCCD_HV_CPU1_ISENSE_N ; 2 = GND
PR220  Q_RES  1 1% CHIP  pkg 0402LF  page 296 : 1 = PVCCD_HV_CPU1_VCC ; 2 = P3V3_AUX
PR224  Q_RES  8.87K 1% EMPTY  pkg 0402LF  page 289 : 1 = PVCCFA_EHV_FIVRA_CPU1_LSET2 ; 2 = GND
PR225  Q_RES  8.87K 1% EMPTY  pkg 0402LF  page 289 : 1 = PVCCFA_EHV_FIVRA_CPU1_LSET1 ; 2 = GND
